# T6G (Grand Teton) — schematic netlist excerpt (pin names and nets, part order shuffled) for the footprints in the layout excerpt that follows; sources: Cadence DE-HDL packaged netlist, KiCad conversion of 04192023_DAF0TMB3IC0_F0TG_MB_C_brd_V02_OCP.brd

PC367  Q_CAP  470PF 50V 10% X7R  pkg 0402  page 217 : A = PVDDIO_P1_TEMP1 ; B = GND
PR2106  Q_RES  10K 1% CHIP  pkg 0402LF  page 262 : A = HSC_VDD ; B = HSC_VIN_UVW_N

U325  MOSFET_N  BSS138K EMPTY  pkg SMLF  page 268
  DRAIN  = IRQ_UV_DETECT_N
  GATE  = A_P12V_STBY_FPH_GATE
  SOURCE  = GND

(kicad_pcb
	(version 20260206)
	(generator "pcbnew")
	(generator_version "10.0")
	(general
		(thickness 1.6)
		(legacy_teardrops no)
	)
	(paper "A4")
	(title_block
		(title "04192023_DAF0TMB3IC0_F0TG_MB_C_brd_V02_OCP.brd")
		(comment 1 "Grand Teton / footprints 3756-3758 of 8354")
	)
	(layers
		(0 "F.Cu" signal "TOP")
		(4 "In1.Cu" signal "GND")
		(6 "In2.Cu" signal "IN1")
		(8 "In3.Cu" signal "GND1")
		(10 "In4.Cu" signal "IN2")
		(12 "In5.Cu" signal "GND2")
		(14 "In6.Cu" signal "IN3")
		(16 "In7.Cu" signal "GND3")
		(18 "In8.Cu" signal "VCC")
		(20 "In9.Cu" signal "VCC1")
		(22 "In10.Cu" signal "GND4")
		(24 "In11.Cu" signal "IN4")
		(26 "In12.Cu" signal "GND5")
		(28 "In13.Cu" signal "IN5")
		(30 "In14.Cu" signal "GND6")
		(32 "In15.Cu" signal "IN6")
		(34 "In16.Cu" signal "GND7")
		(2 "B.Cu" signal "BOTTOM")
		(9 "F.Adhes" user "F.Adhesive")
		(11 "B.Adhes" user "B.Adhesive")
		(13 "F.Paste" user "Package Geometry/Pastemask Top")
		(15 "B.Paste" user "Package Geometry/Pastemask Bottom")
		(5 "F.SilkS" user "Ref Des/Silkscreen Top")
		(7 "B.SilkS" user "Ref Des/Silkscreen Bottom")
		(1 "F.Mask" user "Board Geometry/Soldermask Top")
		(3 "B.Mask" user "Board Geometry/Soldermask Bottom")
		(17 "Dwgs.User" user "User.Drawings")
		(19 "Cmts.User" user "User.Comments")
		(21 "Eco1.User" user "User.Eco1")
		(23 "Eco2.User" user "User.Eco2")
		(25 "Edge.Cuts" user "Board Geometry/Outline")
		(27 "Margin" user)
		(31 "F.CrtYd" user "Package Geometry/Place Bound Top")
		(29 "B.CrtYd" user "Package Geometry/Place Bound Bottom")
		(35 "F.Fab" user "Ref Des/Assembly Top")
		(33 "B.Fab" user "Ref Des/Assembly Bottom")
	)
	(footprint ""
		(layer "F.Cu")
		(at 178.689 -406.527)
		(property "Reference" "PR2106"
			(at 0 0 0)
			(layer "F.SilkS")
			(hide yes)
			(effects
				(font
					(size 1.27 1.27)
				)
			)
		)
		(property "Value" ""
			(at 0 0 0)
			(layer "F.Fab")
			(effects
				(font
					(size 1.27 1.27)
				)
			)
		)
		(duplicate_pad_numbers_are_jumpers no)
		(fp_line
			(start -0.7874 -0.4064)
			(end 0.7874 -0.4064)
			(stroke
				(width 0.1524)
				(type default)
			)
			(layer "F.SilkS")
		)
		(fp_line
			(start -0.7874 0.4064)
			(end -0.7874 -0.4064)
			(stroke
				(width 0.1524)
				(type default)
			)
			(layer "F.SilkS")
		)
		(fp_line
			(start 0.7874 -0.4064)
			(end 0.7874 0.4064)
			(stroke
				(width 0.1524)
				(type default)
			)
			(layer "F.SilkS")
		)
		(fp_line
			(start 0.7874 0.4064)
			(end -0.7874 0.4064)
			(stroke
				(width 0.1524)
				(type default)
			)
			(layer "F.SilkS")
		)
		(fp_line
			(start -0.67945 -0.305054)
			(end -0.12065 -0.305054)
			(stroke
				(width 0.1)
				(type default)
			)
			(layer "F.Fab")
		)
		(fp_line
			(start -0.67945 0.3048)
			(end -0.67945 -0.305054)
			(stroke
				(width 0.1)
				(type default)
			)
			(layer "F.Fab")
		)
		(fp_line
			(start -0.12065 -0.305054)
			(end -0.12065 -0.2794)
			(stroke
				(width 0.1)
				(type default)
			)
			(layer "F.Fab")
		)
		(fp_line
			(start -0.12065 -0.2794)
			(end 0.12065 -0.2794)
			(stroke
				(width 0.1)
				(type default)
			)
			(layer "F.Fab")
		)
		(fp_line
			(start -0.12065 0.2794)
			(end -0.12065 0.3048)
			(stroke
				(width 0.1)
				(type default)
			)
			(layer "F.Fab")
		)
		(fp_line
			(start -0.12065 0.3048)
			(end -0.67945 0.3048)
			(stroke
				(width 0.1)
				(type default)
			)
			(layer "F.Fab")
		)
		(fp_line
			(start 0.120396 0.2794)
			(end -0.12065 0.2794)
			(stroke
				(width 0.1)
				(type default)
			)
			(layer "F.Fab")
		)
		(fp_line
			(start 0.120396 0.3048)
			(end 0.120396 0.2794)
			(stroke
				(width 0.1)
				(type default)
			)
			(layer "F.Fab")
		)
		(fp_line
			(start 0.12065 -0.3048)
			(end 0.67945 -0.3048)
			(stroke
				(width 0.1)
				(type default)
			)
			(layer "F.Fab")
		)
		(fp_line
			(start 0.12065 -0.2794)
			(end 0.12065 -0.3048)
			(stroke
				(width 0.1)
				(type default)
			)
			(layer "F.Fab")
		)
		(fp_line
			(start 0.67945 -0.3048)
			(end 0.67945 0.3048)
			(stroke
				(width 0.1)
				(type default)
			)
			(layer "F.Fab")
		)
		(fp_line
			(start 0.67945 0.3048)
			(end 0.120396 0.3048)
			(stroke
				(width 0.1)
				(type default)
			)
			(layer "F.Fab")
		)
		(pad "1" smd circle
			(at -0.40005 0)
			(size 0 0)
			(layers "F.Cu" "F.Mask" "F.Paste")
			(net "HSC_VDD")
		)
		(pad "2" smd circle
			(at 0.40005 0)
			(size 0 0)
			(layers "F.Cu" "F.Mask" "F.Paste")
			(net "HSC_VIN_UVW_N")
		)
	)
	(footprint ""
		(layer "F.Cu")
		(at 37.211 -363.093)
		(property "Reference" "PC367"
			(at 0 0 0)
			(layer "F.SilkS")
			(hide yes)
			(effects
				(font
					(size 1.27 1.27)
				)
			)
		)
		(property "Value" ""
			(at 0 0 0)
			(layer "F.Fab")
			(effects
				(font
					(size 1.27 1.27)
				)
			)
		)
		(duplicate_pad_numbers_are_jumpers no)
		(fp_line
			(start -0.7874 -0.4064)
			(end 0.7874 -0.4064)
			(stroke
				(width 0.1524)
				(type default)
			)
			(layer "F.SilkS")
		)
		(fp_line
			(start -0.7874 0.4064)
			(end -0.7874 -0.4064)
			(stroke
				(width 0.1524)
				(type default)
			)
			(layer "F.SilkS")
		)
		(fp_line
			(start 0.7874 -0.4064)
			(end 0.7874 0.4064)
			(stroke
				(width 0.1524)
				(type default)
			)
			(layer "F.SilkS")
		)
		(fp_line
			(start 0.7874 0.4064)
			(end -0.7874 0.4064)
			(stroke
				(width 0.1524)
				(type default)
			)
			(layer "F.SilkS")
		)
		(fp_line
			(start -0.67945 -0.305054)
			(end -0.12065 -0.305054)
			(stroke
				(width 0.1)
				(type default)
			)
			(layer "F.Fab")
		)
		(fp_line
			(start -0.67945 0.3048)
			(end -0.67945 -0.305054)
			(stroke
				(width 0.1)
				(type default)
			)
			(layer "F.Fab")
		)
		(fp_line
			(start -0.12065 -0.305054)
			(end -0.12065 -0.2794)
			(stroke
				(width 0.1)
				(type default)
			)
			(layer "F.Fab")
		)
		(fp_line
			(start -0.12065 -0.2794)
			(end 0.12065 -0.2794)
			(stroke
				(width 0.1)
				(type default)
			)
			(layer "F.Fab")
		)
		(fp_line
			(start -0.12065 0.2794)
			(end -0.12065 0.3048)
			(stroke
				(width 0.1)
				(type default)
			)
			(layer "F.Fab")
		)
		(fp_line
			(start -0.12065 0.3048)
			(end -0.67945 0.3048)
			(stroke
				(width 0.1)
				(type default)
			)
			(layer "F.Fab")
		)
		(fp_line
			(start 0.120396 0.2794)
			(end -0.12065 0.2794)
			(stroke
				(width 0.1)
				(type default)
			)
			(layer "F.Fab")
		)
		(fp_line
			(start 0.120396 0.3048)
			(end 0.120396 0.2794)
			(stroke
				(width 0.1)
				(type default)
			)
			(layer "F.Fab")
		)
		(fp_line
			(start 0.12065 -0.3048)
			(end 0.67945 -0.3048)
			(stroke
				(width 0.1)
				(type default)
			)
			(layer "F.Fab")
		)
		(fp_line
			(start 0.12065 -0.2794)
			(end 0.12065 -0.3048)
			(stroke
				(width 0.1)
				(type default)
			)
			(layer "F.Fab")
		)
		(fp_line
			(start 0.67945 -0.3048)
			(end 0.67945 0.3048)
			(stroke
				(width 0.1)
				(type default)
			)
			(layer "F.Fab")
		)
		(fp_line
			(start 0.67945 0.3048)
			(end 0.120396 0.3048)
			(stroke
				(width 0.1)
				(type default)
			)
			(layer "F.Fab")
		)
		(pad "1" smd circle
			(at -0.40005 0)
			(size 0 0)
			(layers "F.Cu" "F.Mask" "F.Paste")
			(net "PVDDIO_P1_TEMP1")
		)
		(pad "2" smd circle
			(at 0.40005 0)
			(size 0 0)
			(layers "F.Cu" "F.Mask" "F.Paste")
			(net "GND")
		)
	)
	(footprint ""
		(layer "F.Cu")
		(at 155.419552 -121.819924 180)
		(property "Reference" "U325"
			(at -0.155956 2.20472 0)
			(unlocked yes)
			(layer "F.SilkS")
			(effects
				(font
					(size 0.7874 0.5842)
					(thickness 0.1524)
				)
			)
		)
		(property "Value" ""
			(at 0 0 180)
			(layer "F.Fab")
			(effects
				(font
					(size 1.27 1.27)
				)
			)
		)
		(duplicate_pad_numbers_are_jumpers no)
		(fp_line
			(start 1.949958 1.610106)
			(end -1.949958 1.610106)
			(stroke
				(width 0.1524)
				(type default)
			)
			(layer "F.SilkS")
		)
		(fp_line
			(start 1.949958 -1.560068)
			(end 1.949958 1.610106)
			(stroke
				(width 0.1524)
				(type default)
			)
			(layer "F.SilkS")
		)
		(fp_line
			(start -1.949958 1.610106)
			(end -1.949958 -1.610106)
			(stroke
				(width 0.1524)
				(type default)
			)
			(layer "F.SilkS")
		)
		(fp_line
			(start -1.949958 -1.610106)
			(end 1.949958 -1.610106)
			(stroke
				(width 0.1524)
				(type default)
			)
			(layer "F.SilkS")
		)
		(fp_line
			(start 0.750062 1.560068)
			(end -0.750062 1.560068)
			(stroke
				(width 0.1)
				(type default)
			)
			(layer "F.Fab")
		)
		(fp_line
			(start 0.750062 -1.560068)
			(end 0.750062 1.560068)
			(stroke
				(width 0.1)
				(type default)
			)
			(layer "F.Fab")
		)
		(fp_line
			(start -0.750062 1.560068)
			(end -0.750062 -1.560068)
			(stroke
				(width 0.1)
				(type default)
			)
			(layer "F.Fab")
		)
		(fp_line
			(start -0.750062 -1.560068)
			(end 0.750062 -1.560068)
			(stroke
				(width 0.1)
				(type default)
			)
			(layer "F.Fab")
		)
		(pad "D" smd rect
			(at 1.100074 0 90)
			(size 1.016 1.4224)
			(layers "F.Cu" "F.Mask" "F.Paste")
			(net "IRQ_UV_DETECT_N")
		)
		(pad "G" smd rect
			(at -1.100074 -0.94996 90)
			(size 1.016 1.4224)
			(layers "F.Cu" "F.Mask" "F.Paste")
			(net "A_P12V_STBY_FPH_GATE")
		)
		(pad "S" smd rect
			(at -1.100074 0.94996 90)
			(size 1.016 1.4224)
			(layers "F.Cu" "F.Mask" "F.Paste")
			(net "GND")
		)
	)
)
